(kicad_pcb
	(version 20260206)
	(generator "pcbnew")
	(generator_version "10.0")
	(general
		(thickness 1.6)
		(legacy_teardrops no)
	)
	(paper "A4")
	(title_block
		(title "01162023_DA0F0TEBIF0_F0T_Expander_BD_F_brd_V02_OCP.brd")
		(comment 1 "Grand Teton / footprints 6080-6081 of 9728")
	)
	(layers
		(0 "F.Cu" signal "TOP")
		(4 "In1.Cu" signal "GND")
		(6 "In2.Cu" signal "VCC")
		(8 "In3.Cu" signal "VCC1")
		(10 "In4.Cu" signal "GND1")
		(12 "In5.Cu" signal "IN1")
		(14 "In6.Cu" signal "GND2")
		(16 "In7.Cu" signal "IN2")
		(18 "In8.Cu" signal "GND3")
		(20 "In9.Cu" signal "IN3")
		(22 "In10.Cu" signal "GND4")
		(24 "In11.Cu" signal "IN4")
		(26 "In12.Cu" signal "GND5")
		(28 "In13.Cu" signal "IN5")
		(30 "In14.Cu" signal "GND6")
		(32 "In15.Cu" signal "IN6")
		(34 "In16.Cu" signal "GND7")
		(2 "B.Cu" signal "BOTTOM")
		(9 "F.Adhes" user "F.Adhesive")
		(11 "B.Adhes" user "B.Adhesive")
		(13 "F.Paste" user "Package Geometry/Pastemask Top")
		(15 "B.Paste" user "Package Geometry/Pastemask Bottom")
		(5 "F.SilkS" user "Ref Des/Silkscreen Top")
		(7 "B.SilkS" user "Ref Des/Silkscreen Bottom")
		(1 "F.Mask" user "Board Geometry/Soldermask Top")
		(3 "B.Mask" user "Board Geometry/Soldermask Bottom")
		(17 "Dwgs.User" user "User.Drawings")
		(19 "Cmts.User" user "User.Comments")
		(21 "Eco1.User" user "User.Eco1")
		(23 "Eco2.User" user "User.Eco2")
		(25 "Edge.Cuts" user "Board Geometry/Outline")
		(27 "Margin" user)
		(31 "F.CrtYd" user "Package Geometry/Place Bound Top")
		(29 "B.CrtYd" user "Package Geometry/Place Bound Bottom")
		(35 "F.Fab" user "Ref Des/Assembly Top")
		(33 "B.Fab" user "Ref Des/Assembly Bottom")
	)
	(footprint ""
		(layer "F.Cu")
		(at 155.064968 -26.785062 180)
		(property "Reference" "J35"
			(at 4.396994 -11.469878 90)
			(unlocked yes)
			(layer "F.SilkS")
			(effects
				(font
					(size 0.7874 0.5842)
					(thickness 0.1524)
				)
			)
		)
		(property "Value" ""
			(at 0 0 180)
			(layer "F.Fab")
			(effects
				(font
					(size 1.27 1.27)
				)
			)
		)
		(duplicate_pad_numbers_are_jumpers no)
		(fp_line
			(start 3.150108 12.115038)
			(end 1.529334 12.115038)
			(stroke
				(width 0.1524)
				(type default)
			)
			(layer "F.SilkS")
		)
		(fp_line
			(start 3.074924 12.014962)
			(end 1.632204 12.014962)
			(stroke
				(width 0.1524)
				(type default)
			)
			(layer "F.SilkS")
		)
		(fp_line
			(start 1.632204 -12.014962)
			(end 3.074924 -12.014962)
			(stroke
				(width 0.1524)
				(type default)
			)
			(layer "F.SilkS")
		)
		(fp_line
			(start 1.529334 -12.115038)
			(end 3.150108 -12.115038)
			(stroke
				(width 0.1524)
				(type default)
			)
			(layer "F.SilkS")
		)
		(fp_line
			(start -1.529334 12.115038)
			(end -3.150108 12.115038)
			(stroke
				(width 0.1524)
				(type default)
			)
			(layer "F.SilkS")
		)
		(fp_line
			(start -1.632204 12.014962)
			(end -3.074924 12.014962)
			(stroke
				(width 0.1524)
				(type default)
			)
			(layer "F.SilkS")
		)
		(fp_line
			(start -3.074924 -12.014962)
			(end -1.632204 -12.014962)
			(stroke
				(width 0.1524)
				(type default)
			)
			(layer "F.SilkS")
		)
		(fp_line
			(start -3.150108 -12.115038)
			(end -1.529334 -12.115038)
			(stroke
				(width 0.1524)
				(type default)
			)
			(layer "F.SilkS")
		)
		(fp_poly
			(pts
				(xy 3.34645 -8.762492) (xy 3.768852 -10.030206) (xy 4.61391 -9.185148)
			)
			(stroke
				(width 0)
				(type default)
			)
			(fill yes)
			(layer "F.SilkS")
		)
		(fp_line
			(start 3.074924 12.014962)
			(end -3.074924 12.014962)
			(stroke
				(width 0.1)
				(type default)
			)
			(layer "F.Fab")
		)
		(fp_line
			(start 3.074924 -12.014962)
			(end 3.074924 12.014962)
			(stroke
				(width 0.1)
				(type default)
			)
			(layer "F.Fab")
		)
		(fp_line
			(start -3.074924 12.014962)
			(end -3.074924 -12.014962)
			(stroke
				(width 0.1)
				(type default)
			)
			(layer "F.Fab")
		)
		(fp_line
			(start -3.074924 -12.014962)
			(end 3.074924 -12.014962)
			(stroke
				(width 0.1)
				(type default)
			)
			(layer "F.Fab")
		)
		(fp_poly
			(pts
				(xy 3.348736 -7.994904) (xy 4.543806 -8.592566) (xy 4.543806 -7.397496)
			)
			(stroke
				(width 0)
				(type default)
			)
			(fill yes)
			(layer "F.Fab")
		)
		(pad "" np_thru_hole circle
			(at -1.75006 -9.815068 90)
			(size 1.1176 1.1176)
			(drill 1.1176)
			(layers "*.Cu" "*.Mask")
			(clearance 0.381)
			(thermal_gap 0.381)
		)
		(pad "" np_thru_hole circle
			(at 0 9.815068 90)
			(size 1.1176 1.1176)
			(drill 1.1176)
			(layers "*.Cu" "*.Mask")
			(clearance 0.381)
			(thermal_gap 0.381)
		)
		(pad "A1" smd rect
			(at 2.29997 -7.994904 90)
			(size 0.381 1.27)
			(layers "F.Cu" "F.Mask" "F.Paste")
			(net "GND")
		)
		(pad "A2" smd rect
			(at 2.29997 -7.394956 90)
			(size 0.381 1.27)
			(layers "F.Cu" "F.Mask" "F.Paste")
			(net "GND")
		)
		(pad "A3" smd rect
			(at 2.29997 -6.795008 90)
			(size 0.381 1.27)
			(layers "F.Cu" "F.Mask" "F.Paste")
			(net "GND")
		)
		(pad "A4" smd rect
			(at 2.29997 -6.19506 90)
			(size 0.381 1.27)
			(layers "F.Cu" "F.Mask" "F.Paste")
			(net "GND")
		)
		(pad "A5" smd rect
			(at 2.29997 -5.595112 90)
			(size 0.381 1.27)
			(layers "F.Cu" "F.Mask" "F.Paste")
			(net "GND")
		)
		(pad "A6" smd rect
			(at 2.29997 -4.99491 90)
			(size 0.381 1.27)
			(layers "F.Cu" "F.Mask" "F.Paste")
			(net "GND")
		)
		(pad "A7" smd rect
			(at 2.29997 -4.394962 90)
			(size 0.381 1.27)
			(layers "F.Cu" "F.Mask" "F.Paste")
			(net "SMB_ISO_SSD5_R_SCL")
		)
		(pad "A8" smd rect
			(at 2.29997 -3.795014 90)
			(size 0.381 1.27)
			(layers "F.Cu" "F.Mask" "F.Paste")
			(net "SMB_ISO_SSD5_R_SDA")
		)
		(pad "A9" smd rect
			(at 2.29997 -3.195066 90)
			(size 0.381 1.27)
			(layers "F.Cu" "F.Mask" "F.Paste")
			(net "RST_SMB_SSD5_ISO_R_N")
		)
		(pad "A10" smd rect
			(at 2.29997 -2.595118 90)
			(size 0.381 1.27)
			(layers "F.Cu" "F.Mask" "F.Paste")
			(net "SSD5_LED_ISO_R_N")
		)
		(pad "A11" smd rect
			(at 2.29997 -1.994916 90)
			(size 0.381 1.27)
			(layers "F.Cu" "F.Mask" "F.Paste")
			(net "PU_CLKREQ5")
		)
		(pad "A12" smd rect
			(at 2.29997 -1.394968 90)
			(size 0.381 1.27)
			(layers "F.Cu" "F.Mask" "F.Paste")
			(net "PRSNT_SSD5_N")
		)
		(pad "A13" smd rect
			(at 2.29997 -0.79502 90)
			(size 0.381 1.27)
			(layers "F.Cu" "F.Mask" "F.Paste")
			(net "GND")
		)
		(pad "A14" smd rect
			(at 2.29997 -0.195072 90)
			(size 0.381 1.27)
			(layers "F.Cu" "F.Mask" "F.Paste")
			(net "Net_8519")
		)
		(pad "A15" smd rect
			(at 2.29997 0.404876 90)
			(size 0.381 1.27)
			(layers "F.Cu" "F.Mask" "F.Paste")
			(net "Net_8518")
		)
		(pad "A16" smd rect
			(at 2.29997 1.005078 90)
			(size 0.381 1.27)
			(layers "F.Cu" "F.Mask" "F.Paste")
			(net "GND")
		)
		(pad "A17" smd rect
			(at 2.29997 1.605026 90)
			(size 0.381 1.27)
			(layers "F.Cu" "F.Mask" "F.Paste")
			(net "P5E_PEX1_STN2_RX_DN<40>")
		)
		(pad "A18" smd rect
			(at 2.29997 2.204974 90)
			(size 0.381 1.27)
			(layers "F.Cu" "F.Mask" "F.Paste")
			(net "P5E_PEX1_STN2_RX_DP<40>")
		)
		(pad "A19" smd rect
			(at 2.29997 2.804922 90)
			(size 0.381 1.27)
			(layers "F.Cu" "F.Mask" "F.Paste")
			(net "GND")
		)
		(pad "A20" smd rect
			(at 2.29997 3.405124 90)
			(size 0.381 1.27)
			(layers "F.Cu" "F.Mask" "F.Paste")
			(net "P5E_PEX1_STN2_RX_DN<41>")
		)
		(pad "A21" smd rect
			(at 2.29997 4.005072 90)
			(size 0.381 1.27)
			(layers "F.Cu" "F.Mask" "F.Paste")
			(net "P5E_PEX1_STN2_RX_DP<41>")
		)
		(pad "A22" smd rect
			(at 2.29997 4.60502 90)
			(size 0.381 1.27)
			(layers "F.Cu" "F.Mask" "F.Paste")
			(net "GND")
		)
		(pad "A23" smd rect
			(at 2.29997 5.204968 90)
			(size 0.381 1.27)
			(layers "F.Cu" "F.Mask" "F.Paste")
			(net "P5E_PEX1_STN2_RX_DN<42>")
		)
		(pad "A24" smd rect
			(at 2.29997 5.804916 90)
			(size 0.381 1.27)
			(layers "F.Cu" "F.Mask" "F.Paste")
			(net "P5E_PEX1_STN2_RX_DP<42>")
		)
		(pad "A25" smd rect
			(at 2.29997 6.405118 90)
			(size 0.381 1.27)
			(layers "F.Cu" "F.Mask" "F.Paste")
			(net "GND")
		)
		(pad "A26" smd rect
			(at 2.29997 7.005066 90)
			(size 0.381 1.27)
			(layers "F.Cu" "F.Mask" "F.Paste")
			(net "P5E_PEX1_STN2_RX_DN<43>")
		)
		(pad "A27" smd rect
			(at 2.29997 7.605014 90)
			(size 0.381 1.27)
			(layers "F.Cu" "F.Mask" "F.Paste")
			(net "P5E_PEX1_STN2_RX_DP<43>")
		)
		(pad "A28" smd rect
			(at 2.29997 8.204962 90)
			(size 0.381 1.27)
			(layers "F.Cu" "F.Mask" "F.Paste")
			(net "GND")
		)
		(pad "B1" smd rect
			(at -2.29997 -7.994904 90)
			(size 0.381 1.27)
			(layers "F.Cu" "F.Mask" "F.Paste")
			(net "P12V_SSD5")
		)
		(pad "B2" smd rect
			(at -2.29997 -7.394956 90)
			(size 0.381 1.27)
			(layers "F.Cu" "F.Mask" "F.Paste")
			(net "P12V_SSD5")
		)
		(pad "B3" smd rect
			(at -2.29997 -6.795008 90)
			(size 0.381 1.27)
			(layers "F.Cu" "F.Mask" "F.Paste")
			(net "P12V_SSD5")
		)
		(pad "B4" smd rect
			(at -2.29997 -6.19506 90)
			(size 0.381 1.27)
			(layers "F.Cu" "F.Mask" "F.Paste")
			(net "P12V_SSD5")
		)
		(pad "B5" smd rect
			(at -2.29997 -5.595112 90)
			(size 0.381 1.27)
			(layers "F.Cu" "F.Mask" "F.Paste")
			(net "P12V_SSD5")
		)
		(pad "B6" smd rect
			(at -2.29997 -4.99491 90)
			(size 0.381 1.27)
			(layers "F.Cu" "F.Mask" "F.Paste")
			(net "P12V_SSD5")
		)
		(pad "B7" smd rect
			(at -2.29997 -4.394962 90)
			(size 0.381 1.27)
			(layers "F.Cu" "F.Mask" "F.Paste")
			(net "Net_8520")
		)
		(pad "B8" smd rect
			(at -2.29997 -3.795014 90)
			(size 0.381 1.27)
			(layers "F.Cu" "F.Mask" "F.Paste")
			(net "Net_8517")
		)
		(pad "B9" smd rect
			(at -2.29997 -3.195066 90)
			(size 0.381 1.27)
			(layers "F.Cu" "F.Mask" "F.Paste")
			(net "DUALPORT_N_SSD5")
		)
		(pad "B10" smd rect
			(at -2.29997 -2.595118 90)
			(size 0.381 1.27)
			(layers "F.Cu" "F.Mask" "F.Paste")
			(net "RST_SSD5_PERST_R_N")
		)
		(pad "B11" smd rect
			(at -2.29997 -1.994916 90)
			(size 0.381 1.27)
			(layers "F.Cu" "F.Mask" "F.Paste")
			(net "P3V3_SSD5")
		)
		(pad "B12" smd rect
			(at -2.29997 -1.394968 90)
			(size 0.381 1.27)
			(layers "F.Cu" "F.Mask" "F.Paste")
			(net "SSD5_PWRDIS_R")
		)
		(pad "B13" smd rect
			(at -2.29997 -0.79502 90)
			(size 0.381 1.27)
			(layers "F.Cu" "F.Mask" "F.Paste")
			(net "GND")
		)
		(pad "B14" smd rect
			(at -2.29997 -0.195072 90)
			(size 0.381 1.27)
			(layers "F.Cu" "F.Mask" "F.Paste")
			(net "CLK_100M_DB800ZL_SSD5_R_DN")
		)
		(pad "B15" smd rect
			(at -2.29997 0.404876 90)
			(size 0.381 1.27)
			(layers "F.Cu" "F.Mask" "F.Paste")
			(net "CLK_100M_DB800ZL_SSD5_R_DP")
		)
		(pad "B16" smd rect
			(at -2.29997 1.005078 90)
			(size 0.381 1.27)
			(layers "F.Cu" "F.Mask" "F.Paste")
			(net "GND")
		)
		(pad "B17" smd rect
			(at -2.29997 1.605026 90)
			(size 0.381 1.27)
			(layers "F.Cu" "F.Mask" "F.Paste")
			(net "P5E_PEX1_STN2_TX_C_DN<40>")
		)
		(pad "B18" smd rect
			(at -2.29997 2.204974 90)
			(size 0.381 1.27)
			(layers "F.Cu" "F.Mask" "F.Paste")
			(net "P5E_PEX1_STN2_TX_C_DP<40>")
		)
		(pad "B19" smd rect
			(at -2.29997 2.804922 90)
			(size 0.381 1.27)
			(layers "F.Cu" "F.Mask" "F.Paste")
			(net "GND")
		)
		(pad "B20" smd rect
			(at -2.29997 3.405124 90)
			(size 0.381 1.27)
			(layers "F.Cu" "F.Mask" "F.Paste")
			(net "P5E_PEX1_STN2_TX_C_DN<41>")
		)
		(pad "B21" smd rect
			(at -2.29997 4.005072 90)
			(size 0.381 1.27)
			(layers "F.Cu" "F.Mask" "F.Paste")
			(net "P5E_PEX1_STN2_TX_C_DP<41>")
		)
		(pad "B22" smd rect
			(at -2.29997 4.60502 90)
			(size 0.381 1.27)
			(layers "F.Cu" "F.Mask" "F.Paste")
			(net "GND")
		)
		(pad "B23" smd rect
			(at -2.29997 5.204968 90)
			(size 0.381 1.27)
			(layers "F.Cu" "F.Mask" "F.Paste")
			(net "P5E_PEX1_STN2_TX_C_DN<42>")
		)
		(pad "B24" smd rect
			(at -2.29997 5.804916 90)
			(size 0.381 1.27)
			(layers "F.Cu" "F.Mask" "F.Paste")
			(net "P5E_PEX1_STN2_TX_C_DP<42>")
		)
		(pad "B25" smd rect
			(at -2.29997 6.405118 90)
			(size 0.381 1.27)
			(layers "F.Cu" "F.Mask" "F.Paste")
			(net "GND")
		)
		(pad "B26" smd rect
			(at -2.29997 7.005066 90)
			(size 0.381 1.27)
			(layers "F.Cu" "F.Mask" "F.Paste")
			(net "P5E_PEX1_STN2_TX_C_DN<43>")
		)
		(pad "B27" smd rect
			(at -2.29997 7.605014 90)
			(size 0.381 1.27)
			(layers "F.Cu" "F.Mask" "F.Paste")
			(net "P5E_PEX1_STN2_TX_C_DP<43>")
		)
		(pad "B28" smd rect
			(at -2.29997 8.204962 90)
			(size 0.381 1.27)
			(layers "F.Cu" "F.Mask" "F.Paste")
			(net "GND")
		)
		(pad "G1" thru_hole oval
			(at 0 -11.364976 90)
			(size 1.6256 3.4798)
			(drill oval 1.1176 2.4638)
			(layers "*.Cu" "*.Mask")
			(remove_unused_layers no)
			(net "GND")
			(clearance 0.127)
			(thermal_gap 0.127)
		)
		(pad "G2" thru_hole oval
			(at 0 11.364976 90)
			(size 1.6256 3.4798)
			(drill oval 1.1176 2.4638)
			(layers "*.Cu" "*.Mask")
			(remove_unused_layers no)
			(net "GND")
			(clearance 0.127)
			(thermal_gap 0.127)
		)
		(zone
			(layer "F.Cu")
			(hatch none 0.5)
			(connect_pads
				(clearance 0)
			)
			(min_thickness 0.25)
			(keepout
				(tracks not_allowed)
				(vias allowed)
				(pads allowed)
				(copperpour not_allowed)
				(footprints allowed)
			)
			(placement
				(enabled no)
				(sheetname "")
			)
			(fill
				(thermal_gap 0.5)
				(thermal_bridge_width 0.5)
				(island_removal_mode 0)
			)
			(polygon
				(pts
					(xy 156.44495 -38.850062) (xy 153.694892 -38.850062) (xy 153.694892 -35.900106) (xy 156.44495 -35.900106)
				)
			)
		)
		(zone
			(layer "F.Cu")
			(hatch none 0.5)
			(connect_pads
				(clearance 0)
			)
			(min_thickness 0.25)
			(keepout
				(tracks not_allowed)
				(vias allowed)
				(pads allowed)
				(copperpour not_allowed)
				(footprints allowed)
			)
			(placement
				(enabled no)
				(sheetname "")
			)
			(fill
				(thermal_gap 0.5)
				(thermal_bridge_width 0.5)
				(island_removal_mode 0)
			)
			(polygon
				(pts
					(xy 157.515052 -17.670018) (xy 153.684986 -17.670018) (xy 153.684986 -14.720062) (xy 157.515052 -14.720062)
				)
			)
		)
		(zone
			(layers "F.Cu" "B.Cu" "In1.Cu" "In2.Cu" "In3.Cu" "In4.Cu" "In5.Cu" "In6.Cu"
				"In7.Cu" "In8.Cu" "In9.Cu" "In10.Cu" "In11.Cu" "In12.Cu" "In13.Cu" "In14.Cu"
				"In15.Cu" "In16.Cu"
			)
			(hatch none 0.5)
			(connect_pads
				(clearance 0)
			)
			(min_thickness 0.25)
			(keepout
				(tracks not_allowed)
				(vias allowed)
				(pads allowed)
				(copperpour not_allowed)
				(footprints allowed)
			)
			(placement
				(enabled no)
				(sheetname "")
			)
			(fill
				(thermal_gap 0.5)
				(thermal_bridge_width 0.5)
				(island_removal_mode 0)
			)
			(polygon
				(pts
					(arc
						(start 156.030168 -36.60013)
						(mid 154.099768 -36.60013)
						(end 156.030168 -36.60013)
					)
				)
			)
		)
		(zone
			(layers "F.Cu" "B.Cu" "In1.Cu" "In2.Cu" "In3.Cu" "In4.Cu" "In5.Cu" "In6.Cu"
				"In7.Cu" "In8.Cu" "In9.Cu" "In10.Cu" "In11.Cu" "In12.Cu" "In13.Cu" "In14.Cu"
				"In15.Cu" "In16.Cu"
			)
			(hatch none 0.5)
			(connect_pads
				(clearance 0)
			)
			(min_thickness 0.25)
			(keepout
				(tracks not_allowed)
				(vias allowed)
				(pads allowed)
				(copperpour not_allowed)
				(footprints allowed)
			)
			(placement
				(enabled no)
				(sheetname "")
			)
			(fill
				(thermal_gap 0.5)
				(thermal_bridge_width 0.5)
				(island_removal_mode 0)
			)
			(polygon
				(pts
					(arc
						(start 157.780228 -16.969994)
						(mid 155.849828 -16.969994)
						(end 157.780228 -16.969994)
					)
				)
			)
		)
	)
	(footprint ""
		(layer "F.Cu")
		(at 392.9253 -356.244906 90)
		(property "Reference" "C754"
			(at 0 0 90)
			(layer "F.SilkS")
			(hide yes)
			(effects
				(font
					(size 1.27 1.27)
				)
			)
		)
		(property "Value" ""
			(at 0 0 90)
			(layer "F.Fab")
			(effects
				(font
					(size 1.27 1.27)
				)
			)
		)
		(duplicate_pad_numbers_are_jumpers no)
		(fp_line
			(start 0.299974 -0.150114)
			(end 0.299974 0.150114)
			(stroke
				(width 0.1)
				(type default)
			)
			(layer "F.Fab")
		)
		(fp_line
			(start -0.299974 -0.150114)
			(end 0.299974 -0.150114)
			(stroke
				(width 0.1)
				(type default)
			)
			(layer "F.Fab")
		)
		(fp_line
			(start 0.299974 0.150114)
			(end -0.299974 0.150114)
			(stroke
				(width 0.1)
				(type default)
			)
			(layer "F.Fab")
		)
		(fp_line
			(start -0.299974 0.150114)
			(end -0.299974 -0.150114)
			(stroke
				(width 0.1)
				(type default)
			)
			(layer "F.Fab")
		)
		(pad "1" smd rect
			(at -0.2667 0 90)
			(size 0.3048 0.381)
			(layers "F.Cu" "F.Mask" "F.Paste")
			(net "P5E_PEX3_STN5_TX_DP<83>")
		)
		(pad "2" smd rect
			(at 0.2667 0 90)
			(size 0.3048 0.381)
			(layers "F.Cu" "F.Mask" "F.Paste")
			(net "P5E_PEX3_STN5_TX_C_DP<83>")
		)
	)
)
